# BASEBOARD_FAB2 (Tioga Pass) — schematic netlist excerpt (pin names and nets, part order shuffled) for the footprints in the layout excerpt that follows; sources: Cadence DE-HDL packaged netlist, KiCad conversion of Wiwynn_Tioga_Pass_MB.brd

R4C12  RES  8.06K 1% CHIP  pkg 0402  page 193 : A = VR_PVCCIOMCP_CPU1_XADDR1 ; B = GND
C4G6  CAP  100.0PF 50V 5% COG  pkg 0402LF  page 233 : A = VR_FB_PVPP_GHJ ; B = VR_COMP_PVPP_GHJ_3
C1A18  CAP  0.220UF 16V 10% X7R  pkg 0402  page 227 : A = VR_PVDDQ_KLM_PH1_BOOT ; B = VR_PVDDQ_KLM_PH1_PHASE

(kicad_pcb
	(version 20260206)
	(generator "pcbnew")
	(generator_version "10.0")
	(general
		(thickness 1.6)
		(legacy_teardrops no)
	)
	(paper "A4")
	(title_block
		(title "Wiwynn_Tioga_Pass_MB.brd")
		(comment 1 "Tioga Pass / footprints 133-135 of 4770")
	)
	(layers
		(0 "F.Cu" signal "TOP")
		(4 "In1.Cu" signal "L2GND")
		(6 "In2.Cu" signal "L3")
		(8 "In3.Cu" signal "L4GND")
		(10 "In4.Cu" signal "L5")
		(12 "In5.Cu" signal "L6GND")
		(14 "In6.Cu" signal "L7VCC")
		(16 "In7.Cu" signal "L8VCC")
		(18 "In8.Cu" signal "L9GND")
		(20 "In9.Cu" signal "L10")
		(22 "In10.Cu" signal "L11GND")
		(24 "In11.Cu" signal "L12")
		(26 "In12.Cu" signal "L13GND")
		(2 "B.Cu" signal "BOTTOM")
		(9 "F.Adhes" user "F.Adhesive")
		(11 "B.Adhes" user "B.Adhesive")
		(13 "F.Paste" user "Package Geometry/Pastemask Top")
		(15 "B.Paste" user "Package Geometry/Pastemask Bottom")
		(5 "F.SilkS" user "Ref Des/Silkscreen Top")
		(7 "B.SilkS" user "Ref Des/Silkscreen Bottom")
		(1 "F.Mask" user "Board Geometry/Soldermask Top")
		(3 "B.Mask" user "Board Geometry/Soldermask Bottom")
		(17 "Dwgs.User" user "User.Drawings")
		(19 "Cmts.User" user "User.Comments")
		(21 "Eco1.User" user "User.Eco1")
		(23 "Eco2.User" user "User.Eco2")
		(25 "Edge.Cuts" user "Board Geometry/Outline")
		(27 "Margin" user)
		(31 "F.CrtYd" user "Package Geometry/Place Bound Top")
		(29 "B.CrtYd" user "Package Geometry/Place Bound Bottom")
		(35 "F.Fab" user "Ref Des/Assembly Top")
		(33 "B.Fab" user "Ref Des/Assembly Bottom")
	)
	(footprint ""
		(layer "F.Cu")
		(at -2.789682 -140.048996 90)
		(property "Reference" "C1A18"
			(at 0 0 90)
			(layer "F.SilkS")
			(hide yes)
			(effects
				(font
					(size 1.27 1.27)
				)
			)
		)
		(property "Value" ""
			(at 0 0 90)
			(layer "F.Fab")
			(effects
				(font
					(size 1.27 1.27)
				)
			)
		)
		(duplicate_pad_numbers_are_jumpers no)
		(fp_poly
			(pts
				(xy 0.3048 -0.1016) (xy 0.3048 0.9906) (xy -0.3048 0.9906) (xy -0.3048 -0.1016)
			)
			(stroke
				(width 0)
				(type default)
			)
			(fill no)
			(layer "F.CrtYd")
		)
		(fp_line
			(start 0.3048 -0.1016)
			(end -0.3048 -0.1016)
			(stroke
				(width 0.1)
				(type default)
			)
			(layer "F.Fab")
		)
		(fp_line
			(start -0.3048 -0.1016)
			(end -0.3048 0.9906)
			(stroke
				(width 0.1)
				(type default)
			)
			(layer "F.Fab")
		)
		(fp_line
			(start 0.3048 0.9906)
			(end 0.3048 -0.1016)
			(stroke
				(width 0.1)
				(type default)
			)
			(layer "F.Fab")
		)
		(fp_line
			(start -0.3048 0.9906)
			(end 0.3048 0.9906)
			(stroke
				(width 0.1)
				(type default)
			)
			(layer "F.Fab")
		)
		(pad "1" smd rect
			(at 0 0 90)
			(size 0.508 0.508)
			(layers "F.Cu" "F.Mask" "F.Paste")
			(net "VR_PVDDQ_KLM_PH1_BOOT")
		)
		(pad "2" smd rect
			(at 0 0.889 90)
			(size 0.508 0.508)
			(layers "F.Cu" "F.Mask" "F.Paste")
			(net "VR_PVDDQ_KLM_PH1_PHASE")
		)
		(zone
			(layer "F.Cu")
			(hatch none 0.5)
			(connect_pads
				(clearance 0)
			)
			(min_thickness 0.25)
			(keepout
				(tracks allowed)
				(vias not_allowed)
				(pads allowed)
				(copperpour not_allowed)
				(footprints allowed)
			)
			(placement
				(enabled no)
				(sheetname "")
			)
			(fill
				(thermal_gap 0.5)
				(thermal_bridge_width 0.5)
				(island_removal_mode 0)
			)
			(polygon
				(pts
					(xy -2.535682 -139.794996) (xy -2.535682 -140.302996) (xy -2.154682 -140.302996) (xy -2.154682 -139.794996)
				)
			)
		)
		(zone
			(layer "F.Cu")
			(hatch none 0.5)
			(connect_pads
				(clearance 0)
			)
			(min_thickness 0.25)
			(keepout
				(tracks not_allowed)
				(vias allowed)
				(pads allowed)
				(copperpour not_allowed)
				(footprints allowed)
			)
			(placement
				(enabled no)
				(sheetname "")
			)
			(fill
				(thermal_gap 0.5)
				(thermal_bridge_width 0.5)
				(island_removal_mode 0)
			)
			(polygon
				(pts
					(xy -2.154682 -139.794996) (xy -2.154682 -140.302996) (xy -2.535682 -140.302996) (xy -2.535682 -139.794996)
				)
			)
		)
	)
	(footprint ""
		(layer "F.Cu")
		(at 176.0855 -8.763 90)
		(property "Reference" "C4G6"
			(at 0 0 90)
			(layer "F.SilkS")
			(hide yes)
			(effects
				(font
					(size 1.27 1.27)
				)
			)
		)
		(property "Value" ""
			(at 0 0 90)
			(layer "F.Fab")
			(effects
				(font
					(size 1.27 1.27)
				)
			)
		)
		(duplicate_pad_numbers_are_jumpers no)
		(fp_poly
			(pts
				(xy 0.3048 -0.1016) (xy 0.3048 0.9906) (xy -0.3048 0.9906) (xy -0.3048 -0.1016)
			)
			(stroke
				(width 0)
				(type default)
			)
			(fill no)
			(layer "F.CrtYd")
		)
		(fp_line
			(start 0.3048 -0.1016)
			(end -0.3048 -0.1016)
			(stroke
				(width 0.1)
				(type default)
			)
			(layer "F.Fab")
		)
		(fp_line
			(start -0.3048 -0.1016)
			(end -0.3048 0.9906)
			(stroke
				(width 0.1)
				(type default)
			)
			(layer "F.Fab")
		)
		(fp_line
			(start 0.3048 0.9906)
			(end 0.3048 -0.1016)
			(stroke
				(width 0.1)
				(type default)
			)
			(layer "F.Fab")
		)
		(fp_line
			(start -0.3048 0.9906)
			(end 0.3048 0.9906)
			(stroke
				(width 0.1)
				(type default)
			)
			(layer "F.Fab")
		)
		(pad "1" smd rect
			(at 0 0 90)
			(size 0.508 0.508)
			(layers "F.Cu" "F.Mask" "F.Paste")
			(net "VR_FB_PVPP_GHJ")
		)
		(pad "2" smd rect
			(at 0 0.889 90)
			(size 0.508 0.508)
			(layers "F.Cu" "F.Mask" "F.Paste")
			(net "VR_COMP_PVPP_GHJ_3")
		)
		(zone
			(layer "F.Cu")
			(hatch none 0.5)
			(connect_pads
				(clearance 0)
			)
			(min_thickness 0.25)
			(keepout
				(tracks allowed)
				(vias not_allowed)
				(pads allowed)
				(copperpour not_allowed)
				(footprints allowed)
			)
			(placement
				(enabled no)
				(sheetname "")
			)
			(fill
				(thermal_gap 0.5)
				(thermal_bridge_width 0.5)
				(island_removal_mode 0)
			)
			(polygon
				(pts
					(xy 176.3395 -8.509) (xy 176.3395 -9.017) (xy 176.7205 -9.017) (xy 176.7205 -8.509)
				)
			)
		)
		(zone
			(layer "F.Cu")
			(hatch none 0.5)
			(connect_pads
				(clearance 0)
			)
			(min_thickness 0.25)
			(keepout
				(tracks not_allowed)
				(vias allowed)
				(pads allowed)
				(copperpour not_allowed)
				(footprints allowed)
			)
			(placement
				(enabled no)
				(sheetname "")
			)
			(fill
				(thermal_gap 0.5)
				(thermal_bridge_width 0.5)
				(island_removal_mode 0)
			)
			(polygon
				(pts
					(xy 176.7205 -8.509) (xy 176.7205 -9.017) (xy 176.3395 -9.017) (xy 176.3395 -8.509)
				)
			)
		)
	)
	(footprint ""
		(layer "F.Cu")
		(at 176.8856 -106.74985)
		(property "Reference" "R4C12"
			(at 0 0 0)
			(layer "F.SilkS")
			(hide yes)
			(effects
				(font
					(size 1.27 1.27)
				)
			)
		)
		(property "Value" ""
			(at 0 0 0)
			(layer "F.Fab")
			(effects
				(font
					(size 1.27 1.27)
				)
			)
		)
		(duplicate_pad_numbers_are_jumpers no)
		(fp_poly
			(pts
				(xy -0.2794 -0.1016) (xy 0.2794 -0.1016) (xy 0.2794 0.9906) (xy -0.2794 0.9906)
			)
			(stroke
				(width 0)
				(type default)
			)
			(fill no)
			(layer "F.CrtYd")
		)
		(fp_line
			(start -0.2794 -0.1016)
			(end -0.2794 0.9906)
			(stroke
				(width 0.1)
				(type default)
			)
			(layer "F.Fab")
		)
		(fp_line
			(start -0.2794 0.9906)
			(end 0.2794 0.9906)
			(stroke
				(width 0.1)
				(type default)
			)
			(layer "F.Fab")
		)
		(fp_line
			(start 0.2794 -0.1016)
			(end -0.2794 -0.1016)
			(stroke
				(width 0.1)
				(type default)
			)
			(layer "F.Fab")
		)
		(fp_line
			(start 0.2794 0.9906)
			(end 0.2794 -0.1016)
			(stroke
				(width 0.1)
				(type default)
			)
			(layer "F.Fab")
		)
		(pad "1" smd rect
			(at 0 0)
			(size 0.508 0.508)
			(layers "F.Cu" "F.Mask" "F.Paste")
			(net "VR_PVCCIOMCP_CPU1_XADDR1")
		)
		(pad "2" smd rect
			(at 0 0.889)
			(size 0.508 0.508)
			(layers "F.Cu" "F.Mask" "F.Paste")
			(net "GND")
		)
		(zone
			(layer "F.Cu")
			(hatch none 0.5)
			(connect_pads
				(clearance 0)
			)
			(min_thickness 0.25)
			(keepout
				(tracks allowed)
				(vias not_allowed)
				(pads allowed)
				(copperpour not_allowed)
				(footprints allowed)
			)
			(placement
				(enabled no)
				(sheetname "")
			)
			(fill
				(thermal_gap 0.5)
				(thermal_bridge_width 0.5)
				(island_removal_mode 0)
			)
			(polygon
				(pts
					(xy 176.6316 -106.49585) (xy 177.1396 -106.49585) (xy 177.1396 -106.11485) (xy 176.6316 -106.11485)
				)
			)
		)
		(zone
			(layer "F.Cu")
			(hatch none 0.5)
			(connect_pads
				(clearance 0)
			)
			(min_thickness 0.25)
			(keepout
				(tracks not_allowed)
				(vias allowed)
				(pads allowed)
				(copperpour not_allowed)
				(footprints allowed)
			)
			(placement
				(enabled no)
				(sheetname "")
			)
			(fill
				(thermal_gap 0.5)
				(thermal_bridge_width 0.5)
				(island_removal_mode 0)
			)
			(polygon
				(pts
					(xy 176.6316 -106.11485) (xy 177.1396 -106.11485) (xy 177.1396 -106.49585) (xy 176.6316 -106.49585)
				)
			)
		)
	)
)
